(kicad_pcb
	(version 20260206)
	(generator "pcbnew")
	(generator_version "10.0")
	(general
		(thickness 1.6)
		(legacy_teardrops no)
	)
	(paper "A4")
	(title_block
		(title "Wiwynn_Tioga_Pass_MB.brd")
		(comment 1 "Tioga Pass / footprint 1664 of 4770 (U7C1), pads 1036-1150 of 1310")
	)
	(layers
		(0 "F.Cu" signal "TOP")
		(4 "In1.Cu" signal "L2GND")
		(6 "In2.Cu" signal "L3")
		(8 "In3.Cu" signal "L4GND")
		(10 "In4.Cu" signal "L5")
		(12 "In5.Cu" signal "L6GND")
		(14 "In6.Cu" signal "L7VCC")
		(16 "In7.Cu" signal "L8VCC")
		(18 "In8.Cu" signal "L9GND")
		(20 "In9.Cu" signal "L10")
		(22 "In10.Cu" signal "L11GND")
		(24 "In11.Cu" signal "L12")
		(26 "In12.Cu" signal "L13GND")
		(2 "B.Cu" signal "BOTTOM")
		(9 "F.Adhes" user "F.Adhesive")
		(11 "B.Adhes" user "B.Adhesive")
		(13 "F.Paste" user "Package Geometry/Pastemask Top")
		(15 "B.Paste" user "Package Geometry/Pastemask Bottom")
		(5 "F.SilkS" user "Ref Des/Silkscreen Top")
		(7 "B.SilkS" user "Ref Des/Silkscreen Bottom")
		(1 "F.Mask" user "Board Geometry/Soldermask Top")
		(3 "B.Mask" user "Board Geometry/Soldermask Bottom")
		(17 "Dwgs.User" user "User.Drawings")
		(19 "Cmts.User" user "User.Comments")
		(21 "Eco1.User" user "User.Eco1")
		(23 "Eco2.User" user "User.Eco2")
		(25 "Edge.Cuts" user "Board Geometry/Outline")
		(27 "Margin" user)
		(31 "F.CrtYd" user "Package Geometry/Place Bound Top")
		(29 "B.CrtYd" user "Package Geometry/Place Bound Bottom")
		(35 "F.Fab" user "Ref Des/Assembly Top")
		(33 "B.Fab" user "Ref Des/Assembly Bottom")
	)
	(footprint ""
		(layer "F.Cu")
		(at 387.985 -109.855 90)
		(property "Reference" "U7C1"
			(at 17.75333 -13.335 0)
			(unlocked yes)
			(layer "F.SilkS")
			(effects
				(font
					(size 0.7874 0.5842)
					(thickness 0.1524)
				)
				(justify left)
			)
		)
		(property "Value" ""
			(at 0 0 90)
			(layer "F.Fab")
			(effects
				(font
					(size 1.27 1.27)
				)
			)
		)
		(duplicate_pad_numbers_are_jumpers no)
		(pad "G11" smd circle
			(at -12.01928 -10.64895)
			(size 0.381 0.381)
			(layers "F.Cu" "F.Mask" "F.Paste")
			(net "FM_CPU0_SKTOCC_LVT3_N")
		)
		(pad "G15" smd circle
			(at -10.30224 -10.64895)
			(size 0.381 0.381)
			(layers "F.Cu" "F.Mask" "F.Paste")
			(net "XDP_PCH_PWR_DEBUG_N")
		)
		(pad "G18" smd circle
			(at -8.5852 -10.64895)
			(size 0.381 0.381)
			(layers "F.Cu" "F.Mask" "F.Paste")
			(net "RST_SRTCRST_N")
		)
		(pad "G22" smd circle
			(at -6.86816 -10.64895)
			(size 0.381 0.381)
			(layers "F.Cu" "F.Mask" "F.Paste")
			(net "GND")
		)
		(pad "G26" smd circle
			(at -5.15112 -10.64895)
			(size 0.381 0.381)
			(layers "F.Cu" "F.Mask" "F.Paste")
			(net "CLK_100M_MEZZ2_DP")
		)
		(pad "G29" smd circle
			(at -3.43408 -10.64895)
			(size 0.381 0.381)
			(layers "F.Cu" "F.Mask" "F.Paste")
			(net "GND")
		)
		(pad "G33" smd circle
			(at -1.71704 -10.64895)
			(size 0.381 0.381)
			(layers "F.Cu" "F.Mask" "F.Paste")
			(net "CLK_100M_PCH_SLOTX24_S0_DP")
		)
		(pad "G37" smd circle
			(at 0 -10.64895)
			(size 0.381 0.381)
			(layers "F.Cu" "F.Mask" "F.Paste")
			(net "GND")
		)
		(pad "G40" smd circle
			(at 1.71704 -10.64895)
			(size 0.381 0.381)
			(layers "F.Cu" "F.Mask" "F.Paste")
			(net "CLK_100M_PCH_SLOTX24_S3_DP")
		)
		(pad "G44" smd circle
			(at 3.43408 -10.64895)
			(size 0.381 0.381)
			(layers "F.Cu" "F.Mask" "F.Paste")
			(net "A_PCH_XCLK_BIASREF")
		)
		(pad "G48" smd circle
			(at 5.15112 -10.64895)
			(size 0.381 0.381)
			(layers "F.Cu" "F.Mask" "F.Paste")
			(net "GND")
		)
		(pad "G52" smd circle
			(at 6.86816 -10.64895)
			(size 0.381 0.381)
			(layers "F.Cu" "F.Mask" "F.Paste")
			(net "P3E_CPU0_PE1_PCH_RXP<0>")
		)
		(pad "G56" smd circle
			(at 8.5852 -10.64895)
			(size 0.381 0.381)
			(layers "F.Cu" "F.Mask" "F.Paste")
			(net "P3E_CPU0_PE1_PCH_RXP<2>")
		)
		(pad "G59" smd circle
			(at 10.30224 -10.64895)
			(size 0.381 0.381)
			(layers "F.Cu" "F.Mask" "F.Paste")
			(net "GND")
		)
		(pad "G63" smd circle
			(at 12.01928 -10.64895)
			(size 0.381 0.381)
			(layers "F.Cu" "F.Mask" "F.Paste")
			(net "GND")
		)
		(pad "G66" smd circle
			(at 13.73632 -10.64895)
			(size 0.381 0.381)
			(layers "F.Cu" "F.Mask" "F.Paste")
			(net "GND")
		)
		(pad "G67" smd circle
			(at 14.356334 -10.891012 90)
			(size 0.3048 0.3048)
			(layers "F.Cu" "F.Mask" "F.Paste")
			(net "TP_PCH_RSVD49")
		)
		(pad "G72" smd circle
			(at 16.310102 -10.876534 45)
			(size 0.4064 0.4064)
			(layers "F.Cu" "F.Mask" "F.Paste")
			(net "GND")
		)
		(pad "H4" smd circle
			(at -15.064994 -10.500106 180)
			(size 0.3048 0.3048)
			(layers "F.Cu" "F.Mask" "F.Paste")
			(net "SPI_PCH_MOSI_R")
		)
		(pad "H9" smd circle
			(at -12.8778 -10.15365)
			(size 0.381 0.381)
			(layers "F.Cu" "F.Mask" "F.Paste")
			(net "FM_BATTERY_SENSE_EN_R_N")
		)
		(pad "H13" smd circle
			(at -11.16076 -10.15365)
			(size 0.381 0.381)
			(layers "F.Cu" "F.Mask" "F.Paste")
			(net "FM_CPU1_SKTOCC_LVT3_N")
		)
		(pad "H17" smd circle
			(at -9.44372 -10.15365)
			(size 0.381 0.381)
			(layers "F.Cu" "F.Mask" "F.Paste")
			(net "XTAL_33K_RTC2")
		)
		(pad "H20" smd circle
			(at -7.72668 -10.15365)
			(size 0.381 0.381)
			(layers "F.Cu" "F.Mask" "F.Paste")
			(net "TP_PCH_HDA_SYNC")
		)
		(pad "H24" smd circle
			(at -6.00964 -10.15365)
			(size 0.381 0.381)
			(layers "F.Cu" "F.Mask" "F.Paste")
			(net "Net_2")
		)
		(pad "H27" smd circle
			(at -4.2926 -10.15365)
			(size 0.381 0.381)
			(layers "F.Cu" "F.Mask" "F.Paste")
			(net "CLK_100M_M2_DP")
		)
		(pad "H31" smd circle
			(at -2.57556 -10.15365)
			(size 0.381 0.381)
			(layers "F.Cu" "F.Mask" "F.Paste")
			(net "CLK_100M_PCH_SLOTX24_S5_DN")
		)
		(pad "H35" smd circle
			(at -0.85852 -10.15365)
			(size 0.381 0.381)
			(layers "F.Cu" "F.Mask" "F.Paste")
			(net "CLK_100M_DB1200_DP")
		)
		(pad "H38" smd circle
			(at 0.85852 -10.15365)
			(size 0.381 0.381)
			(layers "F.Cu" "F.Mask" "F.Paste")
			(net "CLK_100M_AIRMAX8_PE1_DP")
		)
		(pad "H42" smd circle
			(at 2.57556 -10.15365)
			(size 0.381 0.381)
			(layers "F.Cu" "F.Mask" "F.Paste")
			(net "CLK_100M_PCH_SLOTX24_S1_DP")
		)
		(pad "H46" smd circle
			(at 4.2926 -10.15365)
			(size 0.381 0.381)
			(layers "F.Cu" "F.Mask" "F.Paste")
			(net "DMI_CPU0_PCH_RX_DN<0>")
		)
		(pad "H50" smd circle
			(at 6.00964 -10.15365)
			(size 0.381 0.381)
			(layers "F.Cu" "F.Mask" "F.Paste")
			(net "DMI_CPU0_PCH_RX_DP<1>")
		)
		(pad "H54" smd circle
			(at 7.72668 -10.15365)
			(size 0.381 0.381)
			(layers "F.Cu" "F.Mask" "F.Paste")
			(net "P3E_CPU0_PE1_PCH_RXN<2>")
		)
		(pad "H58" smd circle
			(at 9.44372 -10.15365)
			(size 0.381 0.381)
			(layers "F.Cu" "F.Mask" "F.Paste")
			(net "GND")
		)
		(pad "H61" smd circle
			(at 11.16076 -10.15365)
			(size 0.381 0.381)
			(layers "F.Cu" "F.Mask" "F.Paste")
			(net "P3E_CPU0_PE1_PCH_RXN<6>")
		)
		(pad "H65" smd circle
			(at 12.8778 -10.15365)
			(size 0.381 0.381)
			(layers "F.Cu" "F.Mask" "F.Paste")
			(net "GND")
		)
		(pad "H69" smd circle
			(at 15.064994 -10.500106)
			(size 0.3048 0.3048)
			(layers "F.Cu" "F.Mask" "F.Paste")
			(net "TP_PCH_RSVD50")
		)
		(pad "J1" smd circle
			(at -16.310102 -10.063734 90)
			(size 0.3556 0.3556)
			(layers "F.Cu" "F.Mask" "F.Paste")
			(net "GND")
		)
		(pad "J3" smd circle
			(at -15.48003 -9.99998 180)
			(size 0.3048 0.3048)
			(layers "F.Cu" "F.Mask" "F.Paste")
			(net "SPI_PCH_CS0_R_N")
		)
		(pad "J5" smd circle
			(at -14.649958 -9.99998 180)
			(size 0.3048 0.3048)
			(layers "F.Cu" "F.Mask" "F.Paste")
			(net "GND")
		)
		(pad "J7" smd circle
			(at -13.73632 -9.65835)
			(size 0.381 0.381)
			(layers "F.Cu" "F.Mask" "F.Paste")
			(net "GND")
		)
		(pad "J11" smd circle
			(at -12.01928 -9.65835)
			(size 0.381 0.381)
			(layers "F.Cu" "F.Mask" "F.Paste")
			(net "GND")
		)
		(pad "J15" smd circle
			(at -10.30224 -9.65835)
			(size 0.381 0.381)
			(layers "F.Cu" "F.Mask" "F.Paste")
			(net "GND")
		)
		(pad "J18" smd circle
			(at -8.5852 -9.65835)
			(size 0.381 0.381)
			(layers "F.Cu" "F.Mask" "F.Paste")
			(net "GND")
		)
		(pad "J22" smd circle
			(at -6.86816 -9.65835)
			(size 0.381 0.381)
			(layers "F.Cu" "F.Mask" "F.Paste")
			(net "GND")
		)
		(pad "J26" smd circle
			(at -5.15112 -9.65835)
			(size 0.381 0.381)
			(layers "F.Cu" "F.Mask" "F.Paste")
			(net "CLK_100M_MEZZ2_DN")
		)
		(pad "J29" smd circle
			(at -3.43408 -9.65835)
			(size 0.381 0.381)
			(layers "F.Cu" "F.Mask" "F.Paste")
			(net "GND")
		)
		(pad "J33" smd circle
			(at -1.71704 -9.65835)
			(size 0.381 0.381)
			(layers "F.Cu" "F.Mask" "F.Paste")
			(net "CLK_100M_PCH_SLOTX24_S0_DN")
		)
		(pad "J37" smd circle
			(at 0 -9.65835)
			(size 0.381 0.381)
			(layers "F.Cu" "F.Mask" "F.Paste")
			(net "GND")
		)
		(pad "J40" smd circle
			(at 1.71704 -9.65835)
			(size 0.381 0.381)
			(layers "F.Cu" "F.Mask" "F.Paste")
			(net "CLK_100M_PCH_SLOTX24_S3_DN")
		)
		(pad "J44" smd circle
			(at 3.43408 -9.65835)
			(size 0.381 0.381)
			(layers "F.Cu" "F.Mask" "F.Paste")
			(net "GND")
		)
		(pad "J48" smd circle
			(at 5.15112 -9.65835)
			(size 0.381 0.381)
			(layers "F.Cu" "F.Mask" "F.Paste")
			(net "DMI_CPU0_PCH_RX_DN<1>")
		)
		(pad "J52" smd circle
			(at 6.86816 -9.65835)
			(size 0.381 0.381)
			(layers "F.Cu" "F.Mask" "F.Paste")
			(net "P3E_CPU0_PE1_PCH_RXN<0>")
		)
		(pad "J56" smd circle
			(at 8.5852 -9.65835)
			(size 0.381 0.381)
			(layers "F.Cu" "F.Mask" "F.Paste")
			(net "P3E_CPU0_PE1_PCH_RXN<3>")
		)
		(pad "J59" smd circle
			(at 10.30224 -9.65835)
			(size 0.381 0.381)
			(layers "F.Cu" "F.Mask" "F.Paste")
			(net "GND")
		)
		(pad "J63" smd circle
			(at 12.01928 -9.65835)
			(size 0.381 0.381)
			(layers "F.Cu" "F.Mask" "F.Paste")
			(net "P3E_CPU0_PE1_PCH_RXP<6>")
		)
		(pad "J66" smd circle
			(at 13.73632 -9.65835)
			(size 0.381 0.381)
			(layers "F.Cu" "F.Mask" "F.Paste")
			(net "P3E_CPU0_PE1_PCH_R_RXN<9>")
		)
		(pad "J68" smd circle
			(at 14.649958 -9.99998)
			(size 0.3048 0.3048)
			(layers "F.Cu" "F.Mask" "F.Paste")
			(net "GND")
		)
		(pad "J70" smd circle
			(at 15.48003 -9.99998)
			(size 0.3048 0.3048)
			(layers "F.Cu" "F.Mask" "F.Paste")
			(net "GND")
		)
		(pad "J72" smd circle
			(at 16.310102 -10.063734 90)
			(size 0.3556 0.3556)
			(layers "F.Cu" "F.Mask" "F.Paste")
			(net "GND")
		)
		(pad "K2" smd circle
			(at -15.895066 -9.500108 180)
			(size 0.3048 0.3048)
			(layers "F.Cu" "F.Mask" "F.Paste")
			(net "SPI_PCH_CLK")
		)
		(pad "K4" smd circle
			(at -15.064994 -9.500108 180)
			(size 0.3048 0.3048)
			(layers "F.Cu" "F.Mask" "F.Paste")
			(net "SPI_PCH_TPM_CS_N")
		)
		(pad "K9" smd circle
			(at -12.8778 -9.16305)
			(size 0.381 0.381)
			(layers "F.Cu" "F.Mask" "F.Paste")
			(net "IRQ_LVC3_WAKE_N")
		)
		(pad "K13" smd circle
			(at -11.16076 -9.16305)
			(size 0.381 0.381)
			(layers "F.Cu" "F.Mask" "F.Paste")
			(net "PWRGD_DSW_PWROK")
		)
		(pad "K17" smd circle
			(at -9.44372 -9.16305)
			(size 0.381 0.381)
			(layers "F.Cu" "F.Mask" "F.Paste")
			(net "XTAL_33K_RTC1")
		)
		(pad "K20" smd circle
			(at -7.72668 -9.16305)
			(size 0.381 0.381)
			(layers "F.Cu" "F.Mask" "F.Paste")
			(net "TP_PCH_HDA_SDI_0")
		)
		(pad "K24" smd circle
			(at -6.00964 -9.16305)
			(size 0.381 0.381)
			(layers "F.Cu" "F.Mask" "F.Paste")
			(net "Net_1")
		)
		(pad "K27" smd circle
			(at -4.2926 -9.16305)
			(size 0.381 0.381)
			(layers "F.Cu" "F.Mask" "F.Paste")
			(net "CLK_100M_M2_DN")
		)
		(pad "K31" smd circle
			(at -2.57556 -9.16305)
			(size 0.381 0.381)
			(layers "F.Cu" "F.Mask" "F.Paste")
			(net "CLK_100M_PCH_SLOTX24_S5_DP")
		)
		(pad "K35" smd circle
			(at -0.85852 -9.16305)
			(size 0.381 0.381)
			(layers "F.Cu" "F.Mask" "F.Paste")
			(net "CLK_100M_DB1200_DN")
		)
		(pad "K38" smd circle
			(at 0.85852 -9.16305)
			(size 0.381 0.381)
			(layers "F.Cu" "F.Mask" "F.Paste")
			(net "CLK_100M_AIRMAX8_PE1_DN")
		)
		(pad "K42" smd circle
			(at 2.57556 -9.16305)
			(size 0.381 0.381)
			(layers "F.Cu" "F.Mask" "F.Paste")
			(net "CLK_100M_PCH_SLOTX24_S1_DN")
		)
		(pad "K46" smd circle
			(at 4.2926 -9.16305)
			(size 0.381 0.381)
			(layers "F.Cu" "F.Mask" "F.Paste")
			(net "DMI_CPU0_PCH_RX_DP<0>")
		)
		(pad "K50" smd circle
			(at 6.00964 -9.16305)
			(size 0.381 0.381)
			(layers "F.Cu" "F.Mask" "F.Paste")
			(net "DMI_CPU0_PCH_RX_DN<2>")
		)
		(pad "K54" smd circle
			(at 7.72668 -9.16305)
			(size 0.381 0.381)
			(layers "F.Cu" "F.Mask" "F.Paste")
			(net "GND")
		)
		(pad "K58" smd circle
			(at 9.44372 -9.16305)
			(size 0.381 0.381)
			(layers "F.Cu" "F.Mask" "F.Paste")
			(net "P3E_CPU0_PE1_PCH_RXP<3>")
		)
		(pad "K61" smd circle
			(at 11.16076 -9.16305)
			(size 0.381 0.381)
			(layers "F.Cu" "F.Mask" "F.Paste")
			(net "P3E_CPU0_PE1_PCH_RXP<5>")
		)
		(pad "K65" smd circle
			(at 12.8778 -9.16305)
			(size 0.381 0.381)
			(layers "F.Cu" "F.Mask" "F.Paste")
			(net "P3E_CPU0_PE1_PCH_R_RXN<8>")
		)
		(pad "K69" smd circle
			(at 15.064994 -9.500108)
			(size 0.3048 0.3048)
			(layers "F.Cu" "F.Mask" "F.Paste")
			(net "GND")
		)
		(pad "K71" smd circle
			(at 15.895066 -9.500108)
			(size 0.3048 0.3048)
			(layers "F.Cu" "F.Mask" "F.Paste")
			(net "GND")
		)
		(pad "L1" smd oval
			(at -16.310102 -8.999982 180)
			(size 0.254 0.3302)
			(layers "F.Cu" "F.Mask" "F.Paste")
			(net "SPI_PCH_IO3")
		)
		(pad "L3" smd circle
			(at -15.48003 -8.999982 180)
			(size 0.3048 0.3048)
			(layers "F.Cu" "F.Mask" "F.Paste")
			(net "SPI_PCH_MISO")
		)
		(pad "L5" smd circle
			(at -14.649958 -8.999982 180)
			(size 0.3048 0.3048)
			(layers "F.Cu" "F.Mask" "F.Paste")
			(net "GND")
		)
		(pad "L68" smd circle
			(at 14.649958 -8.999982)
			(size 0.3048 0.3048)
			(layers "F.Cu" "F.Mask" "F.Paste")
			(net "GND")
		)
		(pad "L70" smd circle
			(at 15.48003 -8.999982)
			(size 0.3048 0.3048)
			(layers "F.Cu" "F.Mask" "F.Paste")
			(net "SATA6G_PCH_PCIE_UP_SATA_TXN<7>")
		)
		(pad "L72" smd oval
			(at 16.310102 -8.999982 180)
			(size 0.254 0.3302)
			(layers "F.Cu" "F.Mask" "F.Paste")
			(net "SATA6G_PCH_PCIE_UP_SATA_TXP<7>")
		)
		(pad "M2" smd circle
			(at -15.895066 -8.50011 180)
			(size 0.3048 0.3048)
			(layers "F.Cu" "F.Mask" "F.Paste")
			(net "GND")
		)
		(pad "M4" smd circle
			(at -15.064994 -8.50011 180)
			(size 0.3048 0.3048)
			(layers "F.Cu" "F.Mask" "F.Paste")
			(net "GND")
		)
		(pad "M7" smd circle
			(at -13.73632 -8.66775)
			(size 0.381 0.381)
			(layers "F.Cu" "F.Mask" "F.Paste")
			(net "TP_CPU_PCH_TRIGGER_IN")
		)
		(pad "M11" smd circle
			(at -12.01928 -8.66775)
			(size 0.381 0.381)
			(layers "F.Cu" "F.Mask" "F.Paste")
			(net "RST_BMC_SRST_R_N")
		)
		(pad "M15" smd circle
			(at -10.30224 -8.66775)
			(size 0.381 0.381)
			(layers "F.Cu" "F.Mask" "F.Paste")
			(net "TP_SLP_LAN_N")
		)
		(pad "M18" smd circle
			(at -8.5852 -8.66775)
			(size 0.381 0.381)
			(layers "F.Cu" "F.Mask" "F.Paste")
			(net "TP_PCH_HSA_RST_N")
		)
		(pad "M22" smd circle
			(at -6.86816 -8.66775)
			(size 0.381 0.381)
			(layers "F.Cu" "F.Mask" "F.Paste")
			(net "GND")
		)
		(pad "M26" smd circle
			(at -5.15112 -8.66775)
			(size 0.381 0.381)
			(layers "F.Cu" "F.Mask" "F.Paste")
			(net "GND")
		)
		(pad "M29" smd circle
			(at -3.43408 -8.66775)
			(size 0.381 0.381)
			(layers "F.Cu" "F.Mask" "F.Paste")
			(net "GND")
		)
		(pad "M33" smd circle
			(at -1.71704 -8.66775)
			(size 0.381 0.381)
			(layers "F.Cu" "F.Mask" "F.Paste")
			(net "GND")
		)
		(pad "M37" smd circle
			(at 0 -8.66775)
			(size 0.381 0.381)
			(layers "F.Cu" "F.Mask" "F.Paste")
			(net "GND")
		)
		(pad "M40" smd circle
			(at 1.71704 -8.66775)
			(size 0.381 0.381)
			(layers "F.Cu" "F.Mask" "F.Paste")
			(net "GND")
		)
		(pad "M44" smd circle
			(at 3.43408 -8.66775)
			(size 0.381 0.381)
			(layers "F.Cu" "F.Mask" "F.Paste")
			(net "GND")
		)
		(pad "M48" smd circle
			(at 5.15112 -8.66775)
			(size 0.381 0.381)
			(layers "F.Cu" "F.Mask" "F.Paste")
			(net "GND")
		)
		(pad "M52" smd circle
			(at 6.86816 -8.66775)
			(size 0.381 0.381)
			(layers "F.Cu" "F.Mask" "F.Paste")
			(net "DMI_CPU0_PCH_RX_DP<2>")
		)
		(pad "M56" smd circle
			(at 8.5852 -8.66775)
			(size 0.381 0.381)
			(layers "F.Cu" "F.Mask" "F.Paste")
			(net "P3E_CPU0_PE1_PCH_RXP<1>")
		)
		(pad "M59" smd circle
			(at 10.30224 -8.66775)
			(size 0.381 0.381)
			(layers "F.Cu" "F.Mask" "F.Paste")
			(net "P3E_CPU0_PE1_PCH_RXP<4>")
		)
		(pad "M63" smd circle
			(at 12.01928 -8.66775)
			(size 0.381 0.381)
			(layers "F.Cu" "F.Mask" "F.Paste")
			(net "P3E_CPU0_PE1_PCH_R_RXP<8>")
		)
		(pad "M66" smd circle
			(at 13.73632 -8.66775)
			(size 0.381 0.381)
			(layers "F.Cu" "F.Mask" "F.Paste")
			(net "P3E_CPU0_PE1_PCH_R_RXP<9>")
		)
		(pad "M69" smd circle
			(at 15.064994 -8.50011)
			(size 0.3048 0.3048)
			(layers "F.Cu" "F.Mask" "F.Paste")
			(net "SATA6G_PCH_PCIE_UP_SATA_TXN<6>")
		)
		(pad "M71" smd circle
			(at 15.895066 -8.50011)
			(size 0.3048 0.3048)
			(layers "F.Cu" "F.Mask" "F.Paste")
			(net "SATA6G_PCH_PCIE_UP_SATA_TXP<6>")
		)
		(pad "N1" smd oval
			(at -16.310102 -7.999984 180)
			(size 0.254 0.3302)
			(layers "F.Cu" "F.Mask" "F.Paste")
			(net "LPC_LAD1_IO1")
		)
		(pad "N3" smd circle
			(at -15.48003 -7.999984 180)
			(size 0.3048 0.3048)
			(layers "F.Cu" "F.Mask" "F.Paste")
			(net "PU_FM_RCIN_N")
		)
		(pad "N5" smd circle
			(at -14.649958 -7.999984 180)
			(size 0.3048 0.3048)
			(layers "F.Cu" "F.Mask" "F.Paste")
			(net "GND")
		)
		(pad "N9" smd circle
			(at -12.8778 -8.17245)
			(size 0.381 0.381)
			(layers "F.Cu" "F.Mask" "F.Paste")
			(net "GND")
		)
		(pad "N13" smd circle
			(at -11.16076 -8.17245)
			(size 0.381 0.381)
			(layers "F.Cu" "F.Mask" "F.Paste")
			(net "GND")
		)
		(pad "N17" smd circle
			(at -9.44372 -8.17245)
			(size 0.381 0.381)
			(layers "F.Cu" "F.Mask" "F.Paste")
			(net "GND")
		)
		(pad "N20" smd circle
			(at -7.72668 -8.17245)
			(size 0.381 0.381)
			(layers "F.Cu" "F.Mask" "F.Paste")
			(net "GND")
		)
		(pad "N24" smd circle
			(at -6.00964 -8.17245)
			(size 0.381 0.381)
			(layers "F.Cu" "F.Mask" "F.Paste")
			(net "GND")
		)
		(pad "N27" smd circle
			(at -4.2926 -8.17245)
			(size 0.381 0.381)
			(layers "F.Cu" "F.Mask" "F.Paste")
			(net "GND")
		)
	)
)
